(kicad_pcb
	(version 20241229)
	(generator "pcbnew")
	(generator_version "9.0")
	(general
		(thickness 1.552)
		(legacy_teardrops no)
	)
	(paper "A4")
	(title_block
		(date "2023-07-25")
		(rev "1.1.4")
		(comment 9 "footprints 34-37 of 379")
	)
	(layers
		(0 "F.Cu" signal)
		(4 "In1.Cu" signal)
		(6 "In2.Cu" signal)
		(8 "In3.Cu" signal)
		(10 "In4.Cu" signal)
		(12 "In5.Cu" signal)
		(14 "In6.Cu" signal)
		(2 "B.Cu" signal)
		(9 "F.Adhes" user "F.Adhesive")
		(11 "B.Adhes" user "B.Adhesive")
		(13 "F.Paste" user)
		(15 "B.Paste" user)
		(5 "F.SilkS" user "F.Silkscreen")
		(7 "B.SilkS" user "B.Silkscreen")
		(1 "F.Mask" user)
		(3 "B.Mask" user)
		(17 "Dwgs.User" user "User.Drawings")
		(19 "Cmts.User" user "User.Comments")
		(21 "Eco1.User" user "User.Eco1")
		(23 "Eco2.User" user "User.Eco2")
		(25 "Edge.Cuts" user)
		(27 "Margin" user)
		(31 "F.CrtYd" user "F.Courtyard")
		(29 "B.CrtYd" user "B.Courtyard")
		(35 "F.Fab" user)
		(33 "B.Fab" user)
	)
	(footprint "antmicro-footprints:C_0603_1608Metric"
		(layer "F.Cu")
		(at 146.23 70.12 90)
		(descr "Capacitor SMD 0603")
		(tags "capacitor 0603")
		(property "Reference" "C11"
			(at -0.9 -0.51 90)
			(layer "F.SilkS")
			(effects
				(font
					(size 0.65 0.65)
					(thickness 0.15)
				)
				(justify left bottom)
			)
		)
		(property "Value" "C_10u_0603"
			(at 0 1.6 90)
			(layer "F.Fab")
			(hide yes)
			(effects
				(font
					(size 0.7 0.7)
					(thickness 0.15)
				)
				(justify left bottom)
			)
		)
		(property "Datasheet" "https://www.murata.com/products/productdetail?partno=GRM188R61A106KE69%23"
			(at 0 0 90)
			(layer "F.Fab")
			(hide yes)
			(effects
				(font
					(size 1.27 1.27)
					(thickness 0.15)
				)
			)
		)
		(property "Description" "SMD Multilayer Ceramic Capacitor, 10 µF, 10 V, 0603 [1608 Metric], ± 10%, X5R, GRM Series"
			(at 0 0 90)
			(layer "F.Fab")
			(hide yes)
			(effects
				(font
					(size 1.27 1.27)
					(thickness 0.15)
				)
			)
		)
		(property "Author" "Antmicro"
			(at 216.37 -76.09 0)
			(layer "F.Fab")
			(hide yes)
			(effects
				(font
					(size 1 1)
					(thickness 0.15)
				)
			)
		)
		(property "License" "Apache-2.0"
			(at 216.37 -76.09 0)
			(layer "F.Fab")
			(hide yes)
			(effects
				(font
					(size 1 1)
					(thickness 0.15)
				)
			)
		)
		(property "MPN" "GRM188R61A106KE69D"
			(at 216.37 -76.09 0)
			(layer "F.Fab")
			(hide yes)
			(effects
				(font
					(size 1 1)
					(thickness 0.15)
				)
			)
		)
		(property "Manufacturer" "Murata"
			(at 216.37 -76.09 0)
			(layer "F.Fab")
			(hide yes)
			(effects
				(font
					(size 1 1)
					(thickness 0.15)
				)
			)
		)
		(property "Val" "10u"
			(at 216.37 -76.09 0)
			(layer "F.Fab")
			(hide yes)
			(effects
				(font
					(size 1 1)
					(thickness 0.15)
				)
			)
		)
		(property "Voltage" ""
			(at 216.37 -76.09 0)
			(layer "F.Fab")
			(hide yes)
			(effects
				(font
					(size 1 1)
					(thickness 0.15)
				)
			)
		)
		(property "Dielectric" "template_dielectric"
			(at 0 0 90)
			(unlocked yes)
			(layer "F.Fab")
			(hide yes)
			(effects
				(font
					(size 1 1)
					(thickness 0.15)
				)
			)
		)
		(sheetname "/Power Supply/")
		(sheetfile "supply.kicad_sch")
		(attr smd)
		(fp_line
			(start -0.15 -0.4)
			(end 0.15 -0.4)
			(stroke
				(width 0.15)
				(type solid)
			)
			(layer "F.SilkS")
		)
		(fp_line
			(start -0.15 0.4)
			(end 0.15 0.4)
			(stroke
				(width 0.15)
				(type solid)
			)
			(layer "F.SilkS")
		)
		(fp_rect
			(start -1.25 -0.65)
			(end 1.25 0.65)
			(stroke
				(width 0.05)
				(type solid)
			)
			(fill no)
			(layer "F.CrtYd")
		)
		(fp_rect
			(start -0.8 -0.4)
			(end 0.8 0.4)
			(stroke
				(width 0.15)
				(type solid)
			)
			(fill no)
			(layer "F.Fab")
		)
		(fp_text user "License: Apache-2.0"
			(at -1.682 5.895 90)
			(layer "F.Fab")
			(effects
				(font
					(size 0.7 0.7)
					(thickness 0.15)
				)
				(justify left bottom)
			)
		)
		(fp_text user "${REFERENCE}"
			(at -1.682 3.895 90)
			(layer "F.Fab")
			(effects
				(font
					(size 0.7 0.7)
					(thickness 0.15)
				)
				(justify left bottom)
			)
		)
		(fp_text user "Author: Antmicro"
			(at -1.682 4.894 90)
			(layer "F.Fab")
			(effects
				(font
					(size 0.7 0.7)
					(thickness 0.15)
				)
				(justify left bottom)
			)
		)
		(pad "1" smd roundrect
			(at -0.7 0 90)
			(size 0.8 1)
			(layers "F.Cu" "F.Mask" "F.Paste")
			(roundrect_rratio 0.2)
			(net 1 "GND")
			(pintype "passive")
		)
		(pad "2" smd roundrect
			(at 0.7 0 90)
			(size 0.8 1)
			(layers "F.Cu" "F.Mask" "F.Paste")
			(roundrect_rratio 0.2)
			(net 326 "/Power Supply/5V_1V0_IN")
			(pintype "passive")
		)
	)
	(footprint "antmicro-footprints:LED_0603_1608Metric_G"
		(layer "F.Cu")
		(at 165.63 119.15 90)
		(descr "LED SMD 0603 Green")
		(tags "LED SMD 0603 Green")
		(property "Reference" "D3"
			(at -0.09 0.8 90)
			(layer "F.SilkS")
			(effects
				(font
					(size 0.65 0.65)
					(thickness 0.15)
				)
				(justify left top)
			)
		)
		(property "Value" "LED_G_0603_LTST-C190GKT"
			(at 0 1.6 90)
			(layer "F.Fab")
			(hide yes)
			(effects
				(font
					(size 0.7 0.7)
					(thickness 0.15)
				)
				(justify left top)
			)
		)
		(property "Datasheet" "https://media.digikey.com/pdf/Data%20Sheets/Lite-On%20PDFs/LTST-C190GKT.pdf"
			(at 0 0 90)
			(layer "F.Fab")
			(hide yes)
			(effects
				(font
					(size 1.27 1.27)
					(thickness 0.15)
				)
			)
		)
		(property "Description" "LED, Green, SMD, 0603, 20 mA, 2.1 V, 569 nm"
			(at 0 0 90)
			(layer "F.Fab")
			(hide yes)
			(effects
				(font
					(size 1.27 1.27)
					(thickness 0.15)
				)
			)
		)
		(property "Author" "Antmicro"
			(at 46.48 284.78 0)
			(layer "F.Fab")
			(hide yes)
			(effects
				(font
					(size 1 1)
					(thickness 0.15)
				)
			)
		)
		(property "License" "Apache-2.0"
			(at 46.48 284.78 0)
			(layer "F.Fab")
			(hide yes)
			(effects
				(font
					(size 1 1)
					(thickness 0.15)
				)
			)
		)
		(property "MPN" "LTST-C190GKT"
			(at 46.48 284.78 0)
			(layer "F.Fab")
			(hide yes)
			(effects
				(font
					(size 1 1)
					(thickness 0.15)
				)
			)
		)
		(property "Manufacturer" "Lite-On"
			(at 46.48 284.78 0)
			(layer "F.Fab")
			(hide yes)
			(effects
				(font
					(size 1 1)
					(thickness 0.15)
				)
			)
		)
		(property "Color" "Green"
			(at 0 0 90)
			(unlocked yes)
			(layer "F.Fab")
			(hide yes)
			(effects
				(font
					(size 1 1)
					(thickness 0.15)
				)
			)
		)
		(sheetname "/Peripherals/")
		(sheetfile "peripherals.kicad_sch")
		(attr smd)
		(fp_line
			(start 0.22 -0.35)
			(end -0.22 -0.35)
			(stroke
				(width 0.15)
				(type solid)
			)
			(layer "F.SilkS")
		)
		(fp_line
			(start -1.18 -0.319)
			(end -1.18 0.321)
			(stroke
				(width 0.15)
				(type solid)
			)
			(layer "F.SilkS")
		)
		(fp_line
			(start 0.105328 0.001008)
			(end 0.24 0.001)
			(stroke
				(width 0.1)
				(type solid)
			)
			(layer "F.SilkS")
		)
		(fp_line
			(start -0.094672 0.001008)
			(end 0.105328 -0.198992)
			(stroke
				(width 0.1)
				(type solid)
			)
			(layer "F.SilkS")
		)
		(fp_line
			(start -0.094672 0.001008)
			(end -0.24 0.001008)
			(stroke
				(width 0.1)
				(type solid)
			)
			(layer "F.SilkS")
		)
		(fp_line
			(start 0.105328 0.201008)
			(end 0.105328 -0.198992)
			(stroke
				(width 0.1)
				(type solid)
			)
			(layer "F.SilkS")
		)
		(fp_line
			(start 0.105328 0.201008)
			(end -0.094672 0.001008)
			(stroke
				(width 0.1)
				(type solid)
			)
			(layer "F.SilkS")
		)
		(fp_line
			(start -0.094672 0.201008)
			(end -0.094672 -0.198992)
			(stroke
				(width 0.1)
				(type solid)
			)
			(layer "F.SilkS")
		)
		(fp_line
			(start 0.22 0.35)
			(end -0.22 0.35)
			(stroke
				(width 0.15)
				(type solid)
			)
			(layer "F.SilkS")
		)
		(fp_rect
			(start 1.25 0.65)
			(end -1.25 -0.65)
			(stroke
				(width 0.05)
				(type solid)
			)
			(fill no)
			(layer "F.CrtYd")
		)
		(fp_line
			(start 0.201 -0.202)
			(end -0.101 0)
			(stroke
				(width 0.15)
				(type solid)
			)
			(layer "F.Fab")
		)
		(fp_line
			(start -0.199 -0.202)
			(end -0.199 0.1)
			(stroke
				(width 0.15)
				(type solid)
			)
			(layer "F.Fab")
		)
		(fp_line
			(start 0.599 0)
			(end 0.201 0)
			(stroke
				(width 0.15)
				(type solid)
			)
			(layer "F.Fab")
		)
		(fp_line
			(start 0.201 0)
			(end 0.201 -0.202)
			(stroke
				(width 0.15)
				(type solid)
			)
			(layer "F.Fab")
		)
		(fp_line
			(start -0.101 0)
			(end 0.201 0.2)
			(stroke
				(width 0.15)
				(type solid)
			)
			(layer "F.Fab")
		)
		(fp_line
			(start -0.199 0)
			(end -0.597 0)
			(stroke
				(width 0.15)
				(type solid)
			)
			(layer "F.Fab")
		)
		(fp_line
			(start 0.201 0.2)
			(end 0.201 0)
			(stroke
				(width 0.15)
				(type solid)
			)
			(layer "F.Fab")
		)
		(fp_line
			(start -0.199 0.2)
			(end -0.199 0.1)
			(stroke
				(width 0.15)
				(type solid)
			)
			(layer "F.Fab")
		)
		(fp_rect
			(start 0.848 0.4)
			(end -0.85 -0.402)
			(stroke
				(width 0.15)
				(type solid)
			)
			(fill no)
			(layer "F.Fab")
		)
		(fp_text user "${REFERENCE}"
			(at -1.4224 5.999 90)
			(layer "F.Fab")
			(effects
				(font
					(size 0.7 0.7)
					(thickness 0.15)
				)
				(justify left bottom)
			)
		)
		(fp_text user "License: Apache-2.0"
			(at -1.4224 3.599 90)
			(layer "F.Fab")
			(effects
				(font
					(size 0.7 0.7)
					(thickness 0.15)
				)
				(justify left bottom)
			)
		)
		(fp_text user "Author: Antmicro"
			(at -1.4224 4.799 90)
			(layer "F.Fab")
			(effects
				(font
					(size 0.7 0.7)
					(thickness 0.15)
				)
				(justify left bottom)
			)
		)
		(pad "1" smd roundrect
			(at -0.7 0 270)
			(size 0.8 1)
			(layers "F.Cu" "F.Mask" "F.Paste")
			(roundrect_rratio 0.2)
			(net 1 "GND")
			(pinfunction "C")
			(pintype "passive")
		)
		(pad "2" smd roundrect
			(at 0.7 0 270)
			(size 0.8 1)
			(layers "F.Cu" "F.Mask" "F.Paste")
			(roundrect_rratio 0.2)
			(net 63 "Net-(D3-A)")
			(pinfunction "A")
			(pintype "passive")
		)
	)
	(footprint "antmicro-footprints:C_0603_1608Metric"
		(layer "F.Cu")
		(at 138.84 105 -90)
		(descr "Capacitor SMD 0603")
		(tags "capacitor 0603")
		(property "Reference" "C29"
			(at -3.46 -0.39 90)
			(layer "F.SilkS")
			(effects
				(font
					(size 0.65 0.65)
					(thickness 0.15)
				)
				(justify right bottom)
			)
		)
		(property "Value" "C_1u_0603"
			(at 0 1.6 90)
			(layer "F.Fab")
			(hide yes)
			(effects
				(font
					(size 0.7 0.7)
					(thickness 0.15)
				)
				(justify right bottom)
			)
		)
		(property "Datasheet" "https://spicat.kyocera-avx.com/product/mlcc/chartview/0603YD105KAT2A/"
			(at 0 0 90)
			(layer "F.Fab")
			(hide yes)
			(effects
				(font
					(size 1.27 1.27)
					(thickness 0.15)
				)
			)
		)
		(property "Description" "SMD Multilayer Ceramic Capacitor, 1 µF, 16 V, 0603 [1608 Metric], ± 10%, X5R, AVX 0603 MLCC"
			(at 0 0 90)
			(layer "F.Fab")
			(hide yes)
			(effects
				(font
					(size 1.27 1.27)
					(thickness 0.15)
				)
			)
		)
		(property "Author" "Antmicro"
			(at 33.84 243.84 0)
			(layer "F.Fab")
			(hide yes)
			(effects
				(font
					(size 1 1)
					(thickness 0.15)
				)
			)
		)
		(property "Dielectric" ""
			(at 33.84 243.84 0)
			(layer "F.Fab")
			(hide yes)
			(effects
				(font
					(size 1 1)
					(thickness 0.15)
				)
			)
		)
		(property "License" "Apache-2.0"
			(at 33.84 243.84 0)
			(layer "F.Fab")
			(hide yes)
			(effects
				(font
					(size 1 1)
					(thickness 0.15)
				)
			)
		)
		(property "MPN" "0603YD105KAT2A"
			(at 33.84 243.84 0)
			(layer "F.Fab")
			(hide yes)
			(effects
				(font
					(size 1 1)
					(thickness 0.15)
				)
			)
		)
		(property "Manufacturer" "KYOCERA AVX"
			(at 33.84 243.84 0)
			(layer "F.Fab")
			(hide yes)
			(effects
				(font
					(size 1 1)
					(thickness 0.15)
				)
			)
		)
		(property "Val" "1u"
			(at 33.84 243.84 0)
			(layer "F.Fab")
			(hide yes)
			(effects
				(font
					(size 1 1)
					(thickness 0.15)
				)
			)
		)
		(property "Voltage" ""
			(at 33.84 243.84 0)
			(layer "F.Fab")
			(hide yes)
			(effects
				(font
					(size 1 1)
					(thickness 0.15)
				)
			)
		)
		(sheetname "/Power Supply/")
		(sheetfile "supply.kicad_sch")
		(attr smd)
		(fp_line
			(start -0.15 0.4)
			(end 0.15 0.4)
			(stroke
				(width 0.15)
				(type solid)
			)
			(layer "F.SilkS")
		)
		(fp_line
			(start -0.15 -0.4)
			(end 0.15 -0.4)
			(stroke
				(width 0.15)
				(type solid)
			)
			(layer "F.SilkS")
		)
		(fp_rect
			(start -1.25 -0.65)
			(end 1.25 0.65)
			(stroke
				(width 0.05)
				(type solid)
			)
			(fill no)
			(layer "F.CrtYd")
		)
		(fp_rect
			(start -0.8 -0.4)
			(end 0.8 0.4)
			(stroke
				(width 0.15)
				(type solid)
			)
			(fill no)
			(layer "F.Fab")
		)
		(fp_text user "Author: Antmicro"
			(at -1.682 4.894 270)
			(layer "F.Fab")
			(effects
				(font
					(size 0.7 0.7)
					(thickness 0.15)
				)
				(justify left bottom)
			)
		)
		(fp_text user "${REFERENCE}"
			(at -1.682 3.895 270)
			(layer "F.Fab")
			(effects
				(font
					(size 0.7 0.7)
					(thickness 0.15)
				)
				(justify left bottom)
			)
		)
		(fp_text user "License: Apache-2.0"
			(at -1.682 5.895 270)
			(layer "F.Fab")
			(effects
				(font
					(size 0.7 0.7)
					(thickness 0.15)
				)
				(justify left bottom)
			)
		)
		(pad "1" smd roundrect
			(at -0.7 0 270)
			(size 0.8 1)
			(layers "F.Cu" "F.Mask" "F.Paste")
			(roundrect_rratio 0.2)
			(net 1 "GND")
			(pintype "passive")
		)
		(pad "2" smd roundrect
			(at 0.7 0 270)
			(size 0.8 1)
			(layers "F.Cu" "F.Mask" "F.Paste")
			(roundrect_rratio 0.2)
			(net 49 "1V0_Clean")
			(pintype "passive")
		)
	)
	(footprint "antmicro-footprints:R_0402_1005Metric"
		(layer "F.Cu")
		(at 138.49 109.6)
		(descr "Resistor SMD 0402")
		(tags "resistor SMD 0402")
		(property "Reference" "R36"
			(at -3.66 0.34 0)
			(layer "F.SilkS")
			(effects
				(font
					(size 0.65 0.65)
					(thickness 0.15)
				)
				(justify left bottom)
			)
		)
		(property "Value" "R_15k_0402"
			(at 0 1.4 0)
			(layer "F.Fab")
			(hide yes)
			(effects
				(font
					(size 0.7 0.7)
					(thickness 0.15)
				)
				(justify left bottom)
			)
		)
		(property "Datasheet" "https://www.bourns.com/docs/product-datasheets/cr.pdf"
			(at 0 0 0)
			(layer "F.Fab")
			(hide yes)
			(effects
				(font
					(size 1.27 1.27)
					(thickness 0.15)
				)
			)
		)
		(property "Description" "SMD Chip Resistor, 15 kohm, ± 1%, 62.5 mW, 0402 [1005 Metric], Thick Film, General Purpose"
			(at 0 0 0)
			(layer "F.Fab")
			(hide yes)
			(effects
				(font
					(size 1.27 1.27)
					(thickness 0.15)
				)
			)
		)
		(property "Author" "Antmicro"
			(at 0 0 0)
			(layer "F.Fab")
			(hide yes)
			(effects
				(font
					(size 1 1)
					(thickness 0.15)
				)
			)
		)
		(property "License" "Apache-2.0"
			(at 0 0 0)
			(layer "F.Fab")
			(hide yes)
			(effects
				(font
					(size 1 1)
					(thickness 0.15)
				)
			)
		)
		(property "MPN" "CR0402-FX-1502GLF"
			(at 0 0 0)
			(layer "F.Fab")
			(hide yes)
			(effects
				(font
					(size 1 1)
					(thickness 0.15)
				)
			)
		)
		(property "Manufacturer" "Bourns"
			(at 0 0 0)
			(layer "F.Fab")
			(hide yes)
			(effects
				(font
					(size 1 1)
					(thickness 0.15)
				)
			)
		)
		(property "Tolerance" "1%"
			(at 0 0 0)
			(layer "F.Fab")
			(hide yes)
			(effects
				(font
					(size 1 1)
					(thickness 0.15)
				)
			)
		)
		(property "Val" "15k"
			(at 0 0 0)
			(layer "F.Fab")
			(hide yes)
			(effects
				(font
					(size 1 1)
					(thickness 0.15)
				)
			)
		)
		(sheetname "/Power Supply/")
		(sheetfile "supply.kicad_sch")
		(attr smd)
		(fp_rect
			(start -0.925 -0.47)
			(end 0.925 0.47)
			(stroke
				(width 0.05)
				(type default)
			)
			(fill no)
			(layer "F.CrtYd")
		)
		(fp_rect
			(start -0.5 -0.25)
			(end 0.5 0.25)
			(stroke
				(width 0.15)
				(type solid)
			)
			(fill no)
			(layer "F.Fab")
		)
		(fp_text user "${REFERENCE}"
			(at -0.95 3.168 0)
			(layer "F.Fab")
			(effects
				(font
					(size 0.7 0.7)
					(thickness 0.15)
				)
				(justify left bottom)
			)
		)
		(fp_text user "Author: Antmicro"
			(at -0.95 4.169 0)
			(layer "F.Fab")
			(effects
				(font
					(size 0.7 0.7)
					(thickness 0.15)
				)
				(justify left bottom)
			)
		)
		(fp_text user "License: Apache-2.0"
			(at -0.95 5.169 0)
			(layer "F.Fab")
			(effects
				(font
					(size 0.7 0.7)
					(thickness 0.15)
				)
				(justify left bottom)
			)
		)
		(pad "1" smd roundrect
			(at -0.48 0)
			(size 0.59 0.64)
			(layers "F.Cu" "F.Mask" "F.Paste")
			(roundrect_rratio 0.25)
			(net 1 "GND")
			(pintype "passive")
		)
		(pad "2" smd roundrect
			(at 0.48 0)
			(size 0.59 0.64)
			(layers "F.Cu" "F.Mask" "F.Paste")
			(roundrect_rratio 0.25)
			(net 283 "Net-(U10-ADJ)")
			(pintype "passive")
		)
	)
)
